(kicad_pcb
	(version 20260206)
	(generator "pcbnew")
	(generator_version "10.0")
	(general
		(thickness 1.6)
		(legacy_teardrops no)
	)
	(paper "A4")
	(title_block
		(title "Wiwynn_Tioga_Pass_MB.brd")
		(comment 1 "Tioga Pass / footprints 1927-1934 of 4770")
	)
	(layers
		(0 "F.Cu" signal "TOP")
		(4 "In1.Cu" signal "L2GND")
		(6 "In2.Cu" signal "L3")
		(8 "In3.Cu" signal "L4GND")
		(10 "In4.Cu" signal "L5")
		(12 "In5.Cu" signal "L6GND")
		(14 "In6.Cu" signal "L7VCC")
		(16 "In7.Cu" signal "L8VCC")
		(18 "In8.Cu" signal "L9GND")
		(20 "In9.Cu" signal "L10")
		(22 "In10.Cu" signal "L11GND")
		(24 "In11.Cu" signal "L12")
		(26 "In12.Cu" signal "L13GND")
		(2 "B.Cu" signal "BOTTOM")
		(9 "F.Adhes" user "F.Adhesive")
		(11 "B.Adhes" user "B.Adhesive")
		(13 "F.Paste" user "Package Geometry/Pastemask Top")
		(15 "B.Paste" user "Package Geometry/Pastemask Bottom")
		(5 "F.SilkS" user "Ref Des/Silkscreen Top")
		(7 "B.SilkS" user "Ref Des/Silkscreen Bottom")
		(1 "F.Mask" user "Board Geometry/Soldermask Top")
		(3 "B.Mask" user "Board Geometry/Soldermask Bottom")
		(17 "Dwgs.User" user "User.Drawings")
		(19 "Cmts.User" user "User.Comments")
		(21 "Eco1.User" user "User.Eco1")
		(23 "Eco2.User" user "User.Eco2")
		(25 "Edge.Cuts" user "Board Geometry/Outline")
		(27 "Margin" user)
		(31 "F.CrtYd" user "Package Geometry/Place Bound Top")
		(29 "B.CrtYd" user "Package Geometry/Place Bound Bottom")
		(35 "F.Fab" user "Ref Des/Assembly Top")
		(33 "B.Fab" user "Ref Des/Assembly Bottom")
	)
	(footprint ""
		(layer "F.Cu")
		(at 201.671936 11.952478 -90)
		(property "Reference" "T1P1"
			(at 0 0 270)
			(layer "F.SilkS")
			(hide yes)
			(effects
				(font
					(size 1.27 1.27)
				)
			)
		)
		(property "Value" "*"
			(at -3.302 1.12395 270)
			(unlocked yes)
			(layer "F.Fab")
			(hide yes)
			(effects
				(font
					(size 0.889 0.889)
					(thickness 0.1524)
				)
			)
		)
		(property "Device Type" "TPAD-DIFF-4P-GP_DISCRET-GB3-TPA"
			(at -3.302 -0.40005 270)
			(unlocked yes)
			(layer "F.Fab")
			(hide yes)
			(effects
				(font
					(size 0.889 0.889)
					(thickness 0.1524)
				)
			)
		)
		(duplicate_pad_numbers_are_jumpers no)
		(fp_line
			(start -2.286 2.286)
			(end 2.286 2.286)
			(stroke
				(width 0.1524)
				(type default)
			)
			(layer "F.SilkS")
		)
		(fp_line
			(start 2.286 2.286)
			(end 2.286 -2.286)
			(stroke
				(width 0.1524)
				(type default)
			)
			(layer "F.SilkS")
		)
		(fp_line
			(start -2.286 -2.286)
			(end -2.286 2.286)
			(stroke
				(width 0.1524)
				(type default)
			)
			(layer "F.SilkS")
		)
		(fp_line
			(start 2.286 -2.286)
			(end -2.286 -2.286)
			(stroke
				(width 0.1524)
				(type default)
			)
			(layer "F.SilkS")
		)
		(fp_line
			(start -2.413 -2.413)
			(end -2.413 -1.143)
			(stroke
				(width 0.4064)
				(type default)
			)
			(layer "F.SilkS")
		)
		(fp_line
			(start -1.143 -2.413)
			(end -2.413 -2.413)
			(stroke
				(width 0.4064)
				(type default)
			)
			(layer "F.SilkS")
		)
		(fp_rect
			(start -2.54 2.54)
			(end 2.54 -2.54)
			(stroke
				(width 0)
				(type default)
			)
			(fill no)
			(layer "F.CrtYd")
		)
		(fp_rect
			(start -2.54 2.54)
			(end 2.54 -2.54)
			(stroke
				(width 0)
				(type default)
			)
			(fill no)
			(layer "F.Fab")
		)
		(pad "1" thru_hole circle
			(at -1.27 -1.27 270)
			(size 1.524 1.524)
			(drill 0.9144)
			(layers "*.Cu" "*.Mask")
			(remove_unused_layers no)
			(net "L1_85OHM_6INCH_DP")
			(clearance -0.0508)
			(thermal_gap 0.127)
			(padstack
				(mode front_inner_back)
				(layer "Inner"
					(shape circle)
					(size 1.1684 1.1684)
					(clearance 0.127)
				)
				(layer "B.Cu"
					(shape circle)
					(size 1.524 1.524)
					(clearance -0.0508)
				)
			)
		)
		(pad "2" thru_hole circle
			(at 1.27 -1.27 270)
			(size 1.524 1.524)
			(drill 0.9144)
			(layers "*.Cu" "*.Mask")
			(remove_unused_layers no)
			(net "L1_85OHM_6INCH_DN")
			(clearance -0.0508)
			(thermal_gap 0.127)
			(padstack
				(mode front_inner_back)
				(layer "Inner"
					(shape circle)
					(size 1.1684 1.1684)
					(clearance 0.127)
				)
				(layer "B.Cu"
					(shape circle)
					(size 1.524 1.524)
					(clearance -0.0508)
				)
			)
		)
		(pad "GND1" thru_hole rect
			(at -1.27 1.27 270)
			(size 1.524 1.524)
			(drill 0.9144)
			(layers "*.Cu" "*.Mask")
			(remove_unused_layers no)
			(net "GND")
			(clearance -0.0508)
			(thermal_gap 0.127)
			(padstack
				(mode front_inner_back)
				(layer "Inner"
					(shape circle)
					(size 1.1684 1.1684)
					(clearance 0.127)
				)
				(layer "B.Cu"
					(shape rect)
					(size 1.524 1.524)
					(clearance -0.0508)
				)
			)
		)
		(pad "GND2" thru_hole rect
			(at 1.27 1.27 270)
			(size 1.524 1.524)
			(drill 0.9144)
			(layers "*.Cu" "*.Mask")
			(remove_unused_layers no)
			(net "GND")
			(clearance -0.0508)
			(thermal_gap 0.127)
			(padstack
				(mode front_inner_back)
				(layer "Inner"
					(shape circle)
					(size 1.1684 1.1684)
					(clearance 0.127)
				)
				(layer "B.Cu"
					(shape rect)
					(size 1.524 1.524)
					(clearance -0.0508)
				)
			)
		)
	)
	(footprint ""
		(layer "F.Cu")
		(at 171.9834 -138.1125 -90)
		(property "Reference" "L4A1"
			(at -4.43103 4.191 0)
			(unlocked yes)
			(layer "F.SilkS")
			(effects
				(font
					(size 0.7874 0.5842)
					(thickness 0.1524)
				)
				(justify left)
			)
		)
		(property "Value" ""
			(at 0 0 270)
			(layer "F.Fab")
			(effects
				(font
					(size 1.27 1.27)
				)
			)
		)
		(duplicate_pad_numbers_are_jumpers no)
		(fp_line
			(start -3.4036 6.1341)
			(end -3.4036 -0.6731)
			(stroke
				(width 0.1524)
				(type default)
			)
			(layer "F.SilkS")
		)
		(fp_line
			(start -2.5654 6.1341)
			(end -3.4036 6.1341)
			(stroke
				(width 0.1524)
				(type default)
			)
			(layer "F.SilkS")
		)
		(fp_line
			(start 3.4036 6.1341)
			(end 2.5654 6.1341)
			(stroke
				(width 0.1524)
				(type default)
			)
			(layer "F.SilkS")
		)
		(fp_line
			(start -3.4036 -0.6731)
			(end -2.5654 -0.6731)
			(stroke
				(width 0.1524)
				(type default)
			)
			(layer "F.SilkS")
		)
		(fp_line
			(start 2.5654 -0.6731)
			(end 3.4036 -0.6731)
			(stroke
				(width 0.1524)
				(type default)
			)
			(layer "F.SilkS")
		)
		(fp_line
			(start 3.4036 -0.6731)
			(end 3.4036 6.1341)
			(stroke
				(width 0.1524)
				(type default)
			)
			(layer "F.SilkS")
		)
		(fp_poly
			(pts
				(xy -3.4036 -0.6731) (xy -3.4036 6.1341) (xy 3.4036 6.1341) (xy 3.4036 -0.6731)
			)
			(stroke
				(width 0)
				(type default)
			)
			(fill no)
			(layer "F.CrtYd")
		)
		(fp_line
			(start -3.4036 6.1341)
			(end -3.4036 -0.6731)
			(stroke
				(width 0.1)
				(type default)
			)
			(layer "F.Fab")
		)
		(fp_line
			(start 3.4036 6.1341)
			(end -3.4036 6.1341)
			(stroke
				(width 0.1)
				(type default)
			)
			(layer "F.Fab")
		)
		(fp_line
			(start -3.4036 -0.6731)
			(end 3.4036 -0.6731)
			(stroke
				(width 0.1)
				(type default)
			)
			(layer "F.Fab")
		)
		(fp_line
			(start 3.4036 -0.6731)
			(end 3.4036 6.1341)
			(stroke
				(width 0.1)
				(type default)
			)
			(layer "F.Fab")
		)
		(pad "1" smd rect
			(at 0 0 270)
			(size 3.556 3.175)
			(layers "F.Cu" "F.Mask" "F.Paste")
			(net "VR_PVPP_KLM_PHASE")
		)
		(pad "2" smd rect
			(at 0 5.461 270)
			(size 3.556 3.175)
			(layers "F.Cu" "F.Mask" "F.Paste")
			(net "PVPP_KLM")
		)
	)
	(footprint ""
		(layer "F.Cu")
		(at 347.778578 -101.363272 -90)
		(property "Reference" "C7C18"
			(at 0 0 270)
			(layer "F.SilkS")
			(hide yes)
			(effects
				(font
					(size 1.27 1.27)
				)
			)
		)
		(property "Value" ""
			(at 0 0 270)
			(layer "F.Fab")
			(effects
				(font
					(size 1.27 1.27)
				)
			)
		)
		(duplicate_pad_numbers_are_jumpers no)
		(fp_poly
			(pts
				(xy 0.3048 -0.1016) (xy 0.3048 0.9906) (xy -0.3048 0.9906) (xy -0.3048 -0.1016)
			)
			(stroke
				(width 0)
				(type default)
			)
			(fill no)
			(layer "F.CrtYd")
		)
		(fp_line
			(start -0.3048 0.9906)
			(end 0.3048 0.9906)
			(stroke
				(width 0.1)
				(type default)
			)
			(layer "F.Fab")
		)
		(fp_line
			(start 0.3048 0.9906)
			(end 0.3048 -0.1016)
			(stroke
				(width 0.1)
				(type default)
			)
			(layer "F.Fab")
		)
		(fp_line
			(start -0.3048 -0.1016)
			(end -0.3048 0.9906)
			(stroke
				(width 0.1)
				(type default)
			)
			(layer "F.Fab")
		)
		(fp_line
			(start 0.3048 -0.1016)
			(end -0.3048 -0.1016)
			(stroke
				(width 0.1)
				(type default)
			)
			(layer "F.Fab")
		)
		(pad "1" smd rect
			(at 0 0 270)
			(size 0.508 0.508)
			(layers "F.Cu" "F.Mask" "F.Paste")
			(net "P5V_STBY")
		)
		(pad "2" smd rect
			(at 0 0.889 270)
			(size 0.508 0.508)
			(layers "F.Cu" "F.Mask" "F.Paste")
			(net "GND")
		)
		(zone
			(layer "F.Cu")
			(hatch none 0.5)
			(connect_pads
				(clearance 0)
			)
			(min_thickness 0.25)
			(keepout
				(tracks not_allowed)
				(vias allowed)
				(pads allowed)
				(copperpour not_allowed)
				(footprints allowed)
			)
			(placement
				(enabled no)
				(sheetname "")
			)
			(fill
				(thermal_gap 0.5)
				(thermal_bridge_width 0.5)
				(island_removal_mode 0)
			)
			(polygon
				(pts
					(xy 347.143578 -101.617272) (xy 347.143578 -101.109272) (xy 347.524578 -101.109272) (xy 347.524578 -101.617272)
				)
			)
		)
		(zone
			(layer "F.Cu")
			(hatch none 0.5)
			(connect_pads
				(clearance 0)
			)
			(min_thickness 0.25)
			(keepout
				(tracks allowed)
				(vias not_allowed)
				(pads allowed)
				(copperpour not_allowed)
				(footprints allowed)
			)
			(placement
				(enabled no)
				(sheetname "")
			)
			(fill
				(thermal_gap 0.5)
				(thermal_bridge_width 0.5)
				(island_removal_mode 0)
			)
			(polygon
				(pts
					(xy 347.524578 -101.617272) (xy 347.524578 -101.109272) (xy 347.143578 -101.109272) (xy 347.143578 -101.617272)
				)
			)
		)
	)
	(footprint ""
		(layer "F.Cu")
		(at 95.69704 -77.636116)
		(property "Reference" "C2D21"
			(at 0 0 0)
			(layer "F.SilkS")
			(hide yes)
			(effects
				(font
					(size 1.27 1.27)
				)
			)
		)
		(property "Value" ""
			(at 0 0 0)
			(layer "F.Fab")
			(effects
				(font
					(size 1.27 1.27)
				)
			)
		)
		(duplicate_pad_numbers_are_jumpers no)
		(fp_poly
			(pts
				(xy -0.4953 -0.2032) (xy 0.4953 -0.2032) (xy 0.4953 1.6002) (xy -0.4953 1.6002)
			)
			(stroke
				(width 0)
				(type default)
			)
			(fill no)
			(layer "F.CrtYd")
		)
		(fp_line
			(start -0.4953 -0.2032)
			(end 0.4953 -0.2032)
			(stroke
				(width 0.1)
				(type default)
			)
			(layer "F.Fab")
		)
		(fp_line
			(start -0.4953 1.6002)
			(end -0.4953 -0.2032)
			(stroke
				(width 0.1)
				(type default)
			)
			(layer "F.Fab")
		)
		(fp_line
			(start 0.4953 -0.2032)
			(end 0.4953 1.6002)
			(stroke
				(width 0.1)
				(type default)
			)
			(layer "F.Fab")
		)
		(fp_line
			(start 0.4953 1.6002)
			(end -0.4953 1.6002)
			(stroke
				(width 0.1)
				(type default)
			)
			(layer "F.Fab")
		)
		(pad "1" smd rect
			(at 0 0)
			(size 0.762 0.889)
			(layers "F.Cu" "F.Mask" "F.Paste")
			(net "PVCCIN_CPU1")
		)
		(pad "2" smd rect
			(at 0 1.397)
			(size 0.762 0.889)
			(layers "F.Cu" "F.Mask" "F.Paste")
			(net "GND")
		)
		(zone
			(layer "F.Cu")
			(hatch none 0.5)
			(connect_pads
				(clearance 0)
			)
			(min_thickness 0.25)
			(keepout
				(tracks not_allowed)
				(vias allowed)
				(pads allowed)
				(copperpour not_allowed)
				(footprints allowed)
			)
			(placement
				(enabled no)
				(sheetname "")
			)
			(fill
				(thermal_gap 0.5)
				(thermal_bridge_width 0.5)
				(island_removal_mode 0)
			)
			(polygon
				(pts
					(xy 95.31604 -77.191616) (xy 96.07804 -77.191616) (xy 96.07804 -76.683616) (xy 95.31604 -76.683616)
				)
			)
		)
	)
	(footprint ""
		(layer "F.Cu")
		(at 389.439912 -81.906364 90)
		(property "Reference" "C14W2"
			(at -0.8382 -0.67818 90)
			(unlocked yes)
			(layer "F.SilkS")
			(effects
				(font
					(size 0.4064 0.254)
					(thickness 0.1524)
				)
				(justify left)
			)
		)
		(property "Value" ""
			(at 0 0 90)
			(layer "F.Fab")
			(effects
				(font
					(size 1.27 1.27)
				)
			)
		)
		(duplicate_pad_numbers_are_jumpers no)
		(fp_poly
			(pts
				(xy 0.3048 -0.1016) (xy 0.3048 0.9906) (xy -0.3048 0.9906) (xy -0.3048 -0.1016)
			)
			(stroke
				(width 0)
				(type default)
			)
			(fill no)
			(layer "F.CrtYd")
		)
		(fp_line
			(start 0.3048 -0.1016)
			(end -0.3048 -0.1016)
			(stroke
				(width 0.1)
				(type default)
			)
			(layer "F.Fab")
		)
		(fp_line
			(start -0.3048 -0.1016)
			(end -0.3048 0.9906)
			(stroke
				(width 0.1)
				(type default)
			)
			(layer "F.Fab")
		)
		(fp_line
			(start 0.3048 0.9906)
			(end 0.3048 -0.1016)
			(stroke
				(width 0.1)
				(type default)
			)
			(layer "F.Fab")
		)
		(fp_line
			(start -0.3048 0.9906)
			(end 0.3048 0.9906)
			(stroke
				(width 0.1)
				(type default)
			)
			(layer "F.Fab")
		)
		(pad "1" smd rect
			(at 0 0 90)
			(size 0.508 0.508)
			(layers "F.Cu" "F.Mask" "F.Paste")
			(net "P3V3")
		)
		(pad "2" smd rect
			(at 0 0.889 90)
			(size 0.508 0.508)
			(layers "F.Cu" "F.Mask" "F.Paste")
			(net "GND")
		)
		(zone
			(layer "F.Cu")
			(hatch none 0.5)
			(connect_pads
				(clearance 0)
			)
			(min_thickness 0.25)
			(keepout
				(tracks allowed)
				(vias not_allowed)
				(pads allowed)
				(copperpour not_allowed)
				(footprints allowed)
			)
			(placement
				(enabled no)
				(sheetname "")
			)
			(fill
				(thermal_gap 0.5)
				(thermal_bridge_width 0.5)
				(island_removal_mode 0)
			)
			(polygon
				(pts
					(xy 389.693912 -81.652364) (xy 389.693912 -82.160364) (xy 390.074912 -82.160364) (xy 390.074912 -81.652364)
				)
			)
		)
		(zone
			(layer "F.Cu")
			(hatch none 0.5)
			(connect_pads
				(clearance 0)
			)
			(min_thickness 0.25)
			(keepout
				(tracks not_allowed)
				(vias allowed)
				(pads allowed)
				(copperpour not_allowed)
				(footprints allowed)
			)
			(placement
				(enabled no)
				(sheetname "")
			)
			(fill
				(thermal_gap 0.5)
				(thermal_bridge_width 0.5)
				(island_removal_mode 0)
			)
			(polygon
				(pts
					(xy 390.074912 -81.652364) (xy 390.074912 -82.160364) (xy 389.693912 -82.160364) (xy 389.693912 -81.652364)
				)
			)
		)
	)
	(footprint ""
		(layer "F.Cu")
		(at 99.455224 -68.641214 -90)
		(property "Reference" "C2D42"
			(at 0 0 270)
			(layer "F.SilkS")
			(hide yes)
			(effects
				(font
					(size 1.27 1.27)
				)
			)
		)
		(property "Value" ""
			(at 0 0 270)
			(layer "F.Fab")
			(effects
				(font
					(size 1.27 1.27)
				)
			)
		)
		(duplicate_pad_numbers_are_jumpers no)
		(fp_poly
			(pts
				(xy -0.4953 -0.2032) (xy 0.4953 -0.2032) (xy 0.4953 1.6002) (xy -0.4953 1.6002)
			)
			(stroke
				(width 0)
				(type default)
			)
			(fill no)
			(layer "F.CrtYd")
		)
		(fp_line
			(start -0.4953 1.6002)
			(end -0.4953 -0.2032)
			(stroke
				(width 0.1)
				(type default)
			)
			(layer "F.Fab")
		)
		(fp_line
			(start 0.4953 1.6002)
			(end -0.4953 1.6002)
			(stroke
				(width 0.1)
				(type default)
			)
			(layer "F.Fab")
		)
		(fp_line
			(start -0.4953 -0.2032)
			(end 0.4953 -0.2032)
			(stroke
				(width 0.1)
				(type default)
			)
			(layer "F.Fab")
		)
		(fp_line
			(start 0.4953 -0.2032)
			(end 0.4953 1.6002)
			(stroke
				(width 0.1)
				(type default)
			)
			(layer "F.Fab")
		)
		(pad "1" smd rect
			(at 0 0 270)
			(size 0.762 0.889)
			(layers "F.Cu" "F.Mask" "F.Paste")
			(net "PVDDQ_GHJ")
		)
		(pad "2" smd rect
			(at 0 1.397 270)
			(size 0.762 0.889)
			(layers "F.Cu" "F.Mask" "F.Paste")
			(net "GND")
		)
		(zone
			(layer "F.Cu")
			(hatch none 0.5)
			(connect_pads
				(clearance 0)
			)
			(min_thickness 0.25)
			(keepout
				(tracks not_allowed)
				(vias allowed)
				(pads allowed)
				(copperpour not_allowed)
				(footprints allowed)
			)
			(placement
				(enabled no)
				(sheetname "")
			)
			(fill
				(thermal_gap 0.5)
				(thermal_bridge_width 0.5)
				(island_removal_mode 0)
			)
			(polygon
				(pts
					(xy 99.010724 -69.022214) (xy 99.010724 -68.260214) (xy 98.502724 -68.260214) (xy 98.502724 -69.022214)
				)
			)
		)
	)
	(footprint ""
		(layer "F.Cu")
		(at 259.452872 -73.318116)
		(property "Reference" "C5D40"
			(at 0 0 0)
			(layer "F.SilkS")
			(hide yes)
			(effects
				(font
					(size 1.27 1.27)
				)
			)
		)
		(property "Value" ""
			(at 0 0 0)
			(layer "F.Fab")
			(effects
				(font
					(size 1.27 1.27)
				)
			)
		)
		(duplicate_pad_numbers_are_jumpers no)
		(fp_poly
			(pts
				(xy -0.4953 -0.2032) (xy 0.4953 -0.2032) (xy 0.4953 1.6002) (xy -0.4953 1.6002)
			)
			(stroke
				(width 0)
				(type default)
			)
			(fill no)
			(layer "F.CrtYd")
		)
		(fp_line
			(start -0.4953 -0.2032)
			(end 0.4953 -0.2032)
			(stroke
				(width 0.1)
				(type default)
			)
			(layer "F.Fab")
		)
		(fp_line
			(start -0.4953 1.6002)
			(end -0.4953 -0.2032)
			(stroke
				(width 0.1)
				(type default)
			)
			(layer "F.Fab")
		)
		(fp_line
			(start 0.4953 -0.2032)
			(end 0.4953 1.6002)
			(stroke
				(width 0.1)
				(type default)
			)
			(layer "F.Fab")
		)
		(fp_line
			(start 0.4953 1.6002)
			(end -0.4953 1.6002)
			(stroke
				(width 0.1)
				(type default)
			)
			(layer "F.Fab")
		)
		(pad "1" smd rect
			(at 0 0)
			(size 0.762 0.889)
			(layers "F.Cu" "F.Mask" "F.Paste")
			(net "PVCCIN_CPU0")
		)
		(pad "2" smd rect
			(at 0 1.397)
			(size 0.762 0.889)
			(layers "F.Cu" "F.Mask" "F.Paste")
			(net "GND")
		)
		(zone
			(layer "F.Cu")
			(hatch none 0.5)
			(connect_pads
				(clearance 0)
			)
			(min_thickness 0.25)
			(keepout
				(tracks not_allowed)
				(vias allowed)
				(pads allowed)
				(copperpour not_allowed)
				(footprints allowed)
			)
			(placement
				(enabled no)
				(sheetname "")
			)
			(fill
				(thermal_gap 0.5)
				(thermal_bridge_width 0.5)
				(island_removal_mode 0)
			)
			(polygon
				(pts
					(xy 259.071872 -72.873616) (xy 259.833872 -72.873616) (xy 259.833872 -72.365616) (xy 259.071872 -72.365616)
				)
			)
		)
	)
	(footprint ""
		(layer "F.Cu")
		(at 272.861532 -3.3528 90)
		(property "Reference" "C5G17"
			(at 1.848866 0.752348 90)
			(unlocked yes)
			(layer "F.SilkS")
			(effects
				(font
					(size 1.27 0.9652)
					(thickness 0.1524)
				)
			)
		)
		(property "Value" ""
			(at 0 0 90)
			(layer "F.Fab")
			(effects
				(font
					(size 1.27 1.27)
				)
			)
		)
		(duplicate_pad_numbers_are_jumpers no)
		(fp_rect
			(start -0.500126 1.598422)
			(end 0.500126 -0.201422)
			(stroke
				(width 0)
				(type default)
			)
			(fill no)
			(layer "F.CrtYd")
		)
		(fp_line
			(start 0.500126 -0.201422)
			(end 0.500126 1.598422)
			(stroke
				(width 0.1)
				(type default)
			)
			(layer "F.Fab")
		)
		(fp_line
			(start -0.500126 -0.201422)
			(end 0.500126 -0.201422)
			(stroke
				(width 0.1)
				(type default)
			)
			(layer "F.Fab")
		)
		(fp_line
			(start 0.500126 1.598422)
			(end -0.500126 1.598422)
			(stroke
				(width 0.1)
				(type default)
			)
			(layer "F.Fab")
		)
		(fp_line
			(start -0.500126 1.598422)
			(end -0.500126 -0.201422)
			(stroke
				(width 0.1)
				(type default)
			)
			(layer "F.Fab")
		)
		(pad "1" smd rect
			(at 0 0)
			(size 0.889 0.9906)
			(layers "F.Cu" "F.Mask" "F.Paste")
			(net "PVDDQ_ABC")
		)
		(pad "2" smd rect
			(at 0 1.397)
			(size 0.889 0.9906)
			(layers "F.Cu" "F.Mask" "F.Paste")
			(net "GND")
		)
		(zone
			(layer "F.Cu")
			(hatch none 0.5)
			(connect_pads
				(clearance 0)
			)
			(min_thickness 0.25)
			(keepout
				(tracks allowed)
				(vias not_allowed)
				(pads allowed)
				(copperpour not_allowed)
				(footprints allowed)
			)
			(placement
				(enabled no)
				(sheetname "")
			)
			(fill
				(thermal_gap 0.5)
				(thermal_bridge_width 0.5)
				(island_removal_mode 0)
			)
			(polygon
				(pts
					(xy 273.814032 -2.8575) (xy 273.814032 -3.8481) (xy 273.306032 -3.8481) (xy 273.306032 -2.8575)
				)
			)
		)
		(zone
			(layer "F.Cu")
			(hatch none 0.5)
			(connect_pads
				(clearance 0)
			)
			(min_thickness 0.25)
			(keepout
				(tracks not_allowed)
				(vias allowed)
				(pads allowed)
				(copperpour not_allowed)
				(footprints allowed)
			)
			(placement
				(enabled no)
				(sheetname "")
			)
			(fill
				(thermal_gap 0.5)
				(thermal_bridge_width 0.5)
				(island_removal_mode 0)
			)
			(polygon
				(pts
					(xy 273.814032 -2.8575) (xy 273.814032 -3.8481) (xy 273.306032 -3.8481) (xy 273.306032 -2.8575)
				)
			)
		)
	)
)
